# S9S_MB_2U (Grand Teton) — schematic netlist excerpt (pin names and nets, part order shuffled) for the footprints in the layout excerpt that follows; sources: Cadence DE-HDL packaged netlist, KiCad conversion of 03242023_DA0F0TMBIJ0_F0T_Motherboard_J_brd_V01_OCP.brd

R930  Q_RES  4.7K 1% CHIP  pkg 0402LF  page 221 : A = JTAG_BMC_PLD_TCK ; B = GND
PC2218  Q_CAP  0.1UF 25V 10% X7R  pkg 0402  page 192 : A = P3V3_E1S_0_R ; B = GND

(kicad_pcb
	(version 20260206)
	(generator "pcbnew")
	(generator_version "10.0")
	(general
		(thickness 1.6)
		(legacy_teardrops no)
	)
	(paper "A4")
	(title_block
		(title "03242023_DA0F0TMBIJ0_F0T_Motherboard_J_brd_V01_OCP.brd")
		(comment 1 "Grand Teton / footprints 3788-3789 of 6105")
	)
	(layers
		(0 "F.Cu" signal "TOP")
		(4 "In1.Cu" signal "GND")
		(6 "In2.Cu" signal "IN1")
		(8 "In3.Cu" signal "GND1")
		(10 "In4.Cu" signal "IN2")
		(12 "In5.Cu" signal "GND2")
		(14 "In6.Cu" signal "IN3")
		(16 "In7.Cu" signal "GND3")
		(18 "In8.Cu" signal "VCC")
		(20 "In9.Cu" signal "VCC1")
		(22 "In10.Cu" signal "GND4")
		(24 "In11.Cu" signal "IN4")
		(26 "In12.Cu" signal "GND5")
		(28 "In13.Cu" signal "IN5")
		(30 "In14.Cu" signal "GND6")
		(32 "In15.Cu" signal "IN6")
		(34 "In16.Cu" signal "GND7")
		(2 "B.Cu" signal "BOTTOM")
		(9 "F.Adhes" user "F.Adhesive")
		(11 "B.Adhes" user "B.Adhesive")
		(13 "F.Paste" user "Package Geometry/Pastemask Top")
		(15 "B.Paste" user "Package Geometry/Pastemask Bottom")
		(5 "F.SilkS" user "Ref Des/Silkscreen Top")
		(7 "B.SilkS" user "Ref Des/Silkscreen Bottom")
		(1 "F.Mask" user "Board Geometry/Soldermask Top")
		(3 "B.Mask" user "Board Geometry/Soldermask Bottom")
		(17 "Dwgs.User" user "User.Drawings")
		(19 "Cmts.User" user "User.Comments")
		(21 "Eco1.User" user "User.Eco1")
		(23 "Eco2.User" user "User.Eco2")
		(25 "Edge.Cuts" user "Board Geometry/Outline")
		(27 "Margin" user)
		(31 "F.CrtYd" user "Package Geometry/Place Bound Top")
		(29 "B.CrtYd" user "Package Geometry/Place Bound Bottom")
		(35 "F.Fab" user "Ref Des/Assembly Top")
		(33 "B.Fab" user "Ref Des/Assembly Bottom")
	)
	(footprint ""
		(layer "F.Cu")
		(at 116.399056 -66.664078 -90)
		(property "Reference" "R930"
			(at 0 0 270)
			(layer "F.SilkS")
			(hide yes)
			(effects
				(font
					(size 1.27 1.27)
				)
			)
		)
		(property "Value" ""
			(at 0 0 270)
			(layer "F.Fab")
			(effects
				(font
					(size 1.27 1.27)
				)
			)
		)
		(duplicate_pad_numbers_are_jumpers no)
		(fp_line
			(start -0.7874 0.4064)
			(end -0.7874 -0.4064)
			(stroke
				(width 0.1524)
				(type default)
			)
			(layer "F.SilkS")
		)
		(fp_line
			(start 0.7874 0.4064)
			(end -0.7874 0.4064)
			(stroke
				(width 0.1524)
				(type default)
			)
			(layer "F.SilkS")
		)
		(fp_line
			(start -0.7874 -0.4064)
			(end 0.7874 -0.4064)
			(stroke
				(width 0.1524)
				(type default)
			)
			(layer "F.SilkS")
		)
		(fp_line
			(start 0.7874 -0.4064)
			(end 0.7874 0.4064)
			(stroke
				(width 0.1524)
				(type default)
			)
			(layer "F.SilkS")
		)
		(fp_line
			(start -0.67945 0.3048)
			(end -0.67945 -0.305054)
			(stroke
				(width 0.1)
				(type default)
			)
			(layer "F.Fab")
		)
		(fp_line
			(start -0.12065 0.3048)
			(end -0.67945 0.3048)
			(stroke
				(width 0.1)
				(type default)
			)
			(layer "F.Fab")
		)
		(fp_line
			(start 0.120396 0.3048)
			(end 0.120396 0.2794)
			(stroke
				(width 0.1)
				(type default)
			)
			(layer "F.Fab")
		)
		(fp_line
			(start 0.67945 0.3048)
			(end 0.120396 0.3048)
			(stroke
				(width 0.1)
				(type default)
			)
			(layer "F.Fab")
		)
		(fp_line
			(start -0.12065 0.2794)
			(end -0.12065 0.3048)
			(stroke
				(width 0.1)
				(type default)
			)
			(layer "F.Fab")
		)
		(fp_line
			(start 0.120396 0.2794)
			(end -0.12065 0.2794)
			(stroke
				(width 0.1)
				(type default)
			)
			(layer "F.Fab")
		)
		(fp_line
			(start -0.12065 -0.2794)
			(end 0.12065 -0.2794)
			(stroke
				(width 0.1)
				(type default)
			)
			(layer "F.Fab")
		)
		(fp_line
			(start 0.12065 -0.2794)
			(end 0.12065 -0.3048)
			(stroke
				(width 0.1)
				(type default)
			)
			(layer "F.Fab")
		)
		(fp_line
			(start 0.12065 -0.3048)
			(end 0.67945 -0.3048)
			(stroke
				(width 0.1)
				(type default)
			)
			(layer "F.Fab")
		)
		(fp_line
			(start 0.67945 -0.3048)
			(end 0.67945 0.3048)
			(stroke
				(width 0.1)
				(type default)
			)
			(layer "F.Fab")
		)
		(fp_line
			(start -0.67945 -0.305054)
			(end -0.12065 -0.305054)
			(stroke
				(width 0.1)
				(type default)
			)
			(layer "F.Fab")
		)
		(fp_line
			(start -0.12065 -0.305054)
			(end -0.12065 -0.2794)
			(stroke
				(width 0.1)
				(type default)
			)
			(layer "F.Fab")
		)
		(pad "1" smd circle
			(at -0.40005 0 270)
			(size 0 0)
			(layers "F.Cu" "F.Mask" "F.Paste")
			(net "JTAG_BMC_PLD_TCK")
		)
		(pad "2" smd circle
			(at 0.40005 0 270)
			(size 0 0)
			(layers "F.Cu" "F.Mask" "F.Paste")
			(net "GND")
		)
	)
	(footprint ""
		(layer "F.Cu")
		(at 218.336368 -61.072014 180)
		(property "Reference" "PC2218"
			(at 0 0 180)
			(layer "F.SilkS")
			(hide yes)
			(effects
				(font
					(size 1.27 1.27)
				)
			)
		)
		(property "Value" ""
			(at 0 0 180)
			(layer "F.Fab")
			(effects
				(font
					(size 1.27 1.27)
				)
			)
		)
		(duplicate_pad_numbers_are_jumpers no)
		(fp_line
			(start 0.7874 0.4064)
			(end -0.7874 0.4064)
			(stroke
				(width 0.1524)
				(type default)
			)
			(layer "F.SilkS")
		)
		(fp_line
			(start 0.7874 -0.4064)
			(end 0.7874 0.4064)
			(stroke
				(width 0.1524)
				(type default)
			)
			(layer "F.SilkS")
		)
		(fp_line
			(start -0.7874 0.4064)
			(end -0.7874 -0.4064)
			(stroke
				(width 0.1524)
				(type default)
			)
			(layer "F.SilkS")
		)
		(fp_line
			(start -0.7874 -0.4064)
			(end 0.7874 -0.4064)
			(stroke
				(width 0.1524)
				(type default)
			)
			(layer "F.SilkS")
		)
		(fp_line
			(start 0.67945 0.3048)
			(end 0.120396 0.3048)
			(stroke
				(width 0.1)
				(type default)
			)
			(layer "F.Fab")
		)
		(fp_line
			(start 0.67945 -0.3048)
			(end 0.67945 0.3048)
			(stroke
				(width 0.1)
				(type default)
			)
			(layer "F.Fab")
		)
		(fp_line
			(start 0.12065 -0.2794)
			(end 0.12065 -0.3048)
			(stroke
				(width 0.1)
				(type default)
			)
			(layer "F.Fab")
		)
		(fp_line
			(start 0.12065 -0.3048)
			(end 0.67945 -0.3048)
			(stroke
				(width 0.1)
				(type default)
			)
			(layer "F.Fab")
		)
		(fp_line
			(start 0.120396 0.3048)
			(end 0.120396 0.2794)
			(stroke
				(width 0.1)
				(type default)
			)
			(layer "F.Fab")
		)
		(fp_line
			(start 0.120396 0.2794)
			(end -0.12065 0.2794)
			(stroke
				(width 0.1)
				(type default)
			)
			(layer "F.Fab")
		)
		(fp_line
			(start -0.12065 0.3048)
			(end -0.67945 0.3048)
			(stroke
				(width 0.1)
				(type default)
			)
			(layer "F.Fab")
		)
		(fp_line
			(start -0.12065 0.2794)
			(end -0.12065 0.3048)
			(stroke
				(width 0.1)
				(type default)
			)
			(layer "F.Fab")
		)
		(fp_line
			(start -0.12065 -0.2794)
			(end 0.12065 -0.2794)
			(stroke
				(width 0.1)
				(type default)
			)
			(layer "F.Fab")
		)
		(fp_line
			(start -0.12065 -0.305054)
			(end -0.12065 -0.2794)
			(stroke
				(width 0.1)
				(type default)
			)
			(layer "F.Fab")
		)
		(fp_line
			(start -0.67945 0.3048)
			(end -0.67945 -0.305054)
			(stroke
				(width 0.1)
				(type default)
			)
			(layer "F.Fab")
		)
		(fp_line
			(start -0.67945 -0.305054)
			(end -0.12065 -0.305054)
			(stroke
				(width 0.1)
				(type default)
			)
			(layer "F.Fab")
		)
		(pad "1" smd circle
			(at -0.40005 0 180)
			(size 0 0)
			(layers "F.Cu" "F.Mask" "F.Paste")
			(net "P3V3_E1S_0_R")
		)
		(pad "2" smd circle
			(at 0.40005 0 180)
			(size 0 0)
			(layers "F.Cu" "F.Mask" "F.Paste")
			(net "GND")
		)
	)
)
